(kicad_pcb
	(version 20260206)
	(generator "pcbnew")
	(generator_version "10.0")
	(general
		(thickness 1.6)
		(legacy_teardrops no)
	)
	(paper "A4")
	(title_block
		(title "Wiwynn_Tioga_Pass_MB.brd")
		(comment 1 "Tioga Pass / footprints 1603-1608 of 4770")
	)
	(layers
		(0 "F.Cu" signal "TOP")
		(4 "In1.Cu" signal "L2GND")
		(6 "In2.Cu" signal "L3")
		(8 "In3.Cu" signal "L4GND")
		(10 "In4.Cu" signal "L5")
		(12 "In5.Cu" signal "L6GND")
		(14 "In6.Cu" signal "L7VCC")
		(16 "In7.Cu" signal "L8VCC")
		(18 "In8.Cu" signal "L9GND")
		(20 "In9.Cu" signal "L10")
		(22 "In10.Cu" signal "L11GND")
		(24 "In11.Cu" signal "L12")
		(26 "In12.Cu" signal "L13GND")
		(2 "B.Cu" signal "BOTTOM")
		(9 "F.Adhes" user "F.Adhesive")
		(11 "B.Adhes" user "B.Adhesive")
		(13 "F.Paste" user "Package Geometry/Pastemask Top")
		(15 "B.Paste" user "Package Geometry/Pastemask Bottom")
		(5 "F.SilkS" user "Ref Des/Silkscreen Top")
		(7 "B.SilkS" user "Ref Des/Silkscreen Bottom")
		(1 "F.Mask" user "Board Geometry/Soldermask Top")
		(3 "B.Mask" user "Board Geometry/Soldermask Bottom")
		(17 "Dwgs.User" user "User.Drawings")
		(19 "Cmts.User" user "User.Comments")
		(21 "Eco1.User" user "User.Eco1")
		(23 "Eco2.User" user "User.Eco2")
		(25 "Edge.Cuts" user "Board Geometry/Outline")
		(27 "Margin" user)
		(31 "F.CrtYd" user "Package Geometry/Place Bound Top")
		(29 "B.CrtYd" user "Package Geometry/Place Bound Bottom")
		(35 "F.Fab" user "Ref Des/Assembly Top")
		(33 "B.Fab" user "Ref Des/Assembly Bottom")
	)
	(footprint ""
		(layer "F.Cu")
		(at 494.18494 -124.25172 90)
		(property "Reference" "R1M9"
			(at 0 0 90)
			(layer "F.SilkS")
			(hide yes)
			(effects
				(font
					(size 1.27 1.27)
				)
			)
		)
		(property "Value" ""
			(at 0 0 90)
			(layer "F.Fab")
			(effects
				(font
					(size 1.27 1.27)
				)
			)
		)
		(duplicate_pad_numbers_are_jumpers no)
		(fp_rect
			(start 0.2794 -0.1016)
			(end -0.2794 0.9906)
			(stroke
				(width 0)
				(type default)
			)
			(fill no)
			(layer "F.CrtYd")
		)
		(fp_line
			(start 0.2794 -0.1016)
			(end -0.2794 -0.1016)
			(stroke
				(width 0.1)
				(type default)
			)
			(layer "F.Fab")
		)
		(fp_line
			(start -0.2794 -0.1016)
			(end -0.2794 0.9906)
			(stroke
				(width 0.1)
				(type default)
			)
			(layer "F.Fab")
		)
		(fp_line
			(start 0.2794 0.9906)
			(end 0.2794 -0.1016)
			(stroke
				(width 0.1)
				(type default)
			)
			(layer "F.Fab")
		)
		(fp_line
			(start -0.2794 0.9906)
			(end 0.2794 0.9906)
			(stroke
				(width 0.1)
				(type default)
			)
			(layer "F.Fab")
		)
		(pad "1" smd rect
			(at 0 0 90)
			(size 0.508 0.508)
			(layers "F.Cu" "F.Mask" "F.Paste")
			(net "SMB_SENSOR_TMP421_1_SDA")
		)
		(pad "2" smd rect
			(at 0 0.889 90)
			(size 0.508 0.508)
			(layers "F.Cu" "F.Mask" "F.Paste")
			(net "SMB_SENSOR_STBY_LVC3_SDA")
		)
		(zone
			(layer "F.Cu")
			(hatch none 0.5)
			(connect_pads
				(clearance 0)
			)
			(min_thickness 0.25)
			(keepout
				(tracks not_allowed)
				(vias allowed)
				(pads allowed)
				(copperpour not_allowed)
				(footprints allowed)
			)
			(placement
				(enabled no)
				(sheetname "")
			)
			(fill
				(thermal_gap 0.5)
				(thermal_bridge_width 0.5)
				(island_removal_mode 0)
			)
			(polygon
				(pts
					(xy 494.43894 -124.50572) (xy 494.43894 -123.99772) (xy 494.81994 -123.99772) (xy 494.81994 -124.50572)
				)
			)
		)
		(zone
			(layer "F.Cu")
			(hatch none 0.5)
			(connect_pads
				(clearance 0)
			)
			(min_thickness 0.25)
			(keepout
				(tracks allowed)
				(vias not_allowed)
				(pads allowed)
				(copperpour not_allowed)
				(footprints allowed)
			)
			(placement
				(enabled no)
				(sheetname "")
			)
			(fill
				(thermal_gap 0.5)
				(thermal_bridge_width 0.5)
				(island_removal_mode 0)
			)
			(polygon
				(pts
					(xy 494.43894 -124.50572) (xy 494.43894 -123.99772) (xy 494.81994 -123.99772) (xy 494.81994 -124.50572)
				)
			)
		)
	)
	(footprint ""
		(layer "F.Cu")
		(at 193.0146 -98.7298 90)
		(property "Reference" "RT40"
			(at 1.01473 0.656336 0)
			(unlocked yes)
			(layer "F.SilkS")
			(effects
				(font
					(size 0.4064 0.254)
					(thickness 0.1524)
				)
			)
		)
		(property "Value" ""
			(at 0 0 90)
			(layer "F.Fab")
			(effects
				(font
					(size 1.27 1.27)
				)
			)
		)
		(duplicate_pad_numbers_are_jumpers no)
		(fp_poly
			(pts
				(xy -0.4953 -0.2032) (xy 0.4953 -0.2032) (xy 0.4953 1.6002) (xy -0.4953 1.6002)
			)
			(stroke
				(width 0)
				(type default)
			)
			(fill no)
			(layer "F.CrtYd")
		)
		(fp_line
			(start 0.4953 -0.2032)
			(end 0.4953 1.6002)
			(stroke
				(width 0.1)
				(type default)
			)
			(layer "F.Fab")
		)
		(fp_line
			(start -0.4953 -0.2032)
			(end 0.4953 -0.2032)
			(stroke
				(width 0.1)
				(type default)
			)
			(layer "F.Fab")
		)
		(fp_line
			(start 0.4953 1.6002)
			(end -0.4953 1.6002)
			(stroke
				(width 0.1)
				(type default)
			)
			(layer "F.Fab")
		)
		(fp_line
			(start -0.4953 1.6002)
			(end -0.4953 -0.2032)
			(stroke
				(width 0.1)
				(type default)
			)
			(layer "F.Fab")
		)
		(pad "1" smd rect
			(at 0 0 90)
			(size 0.762 0.889)
			(layers "F.Cu" "F.Mask" "F.Paste")
			(net "VR_PVSA_CPU0_BOOT")
		)
		(pad "2" smd rect
			(at 0 1.397 90)
			(size 0.762 0.889)
			(layers "F.Cu" "F.Mask" "F.Paste")
			(net "VR_PVSA_CPU0_BOOT_R")
		)
		(zone
			(layer "F.Cu")
			(hatch none 0.5)
			(connect_pads
				(clearance 0)
			)
			(min_thickness 0.25)
			(keepout
				(tracks allowed)
				(vias not_allowed)
				(pads allowed)
				(copperpour not_allowed)
				(footprints allowed)
			)
			(placement
				(enabled no)
				(sheetname "")
			)
			(fill
				(thermal_gap 0.5)
				(thermal_bridge_width 0.5)
				(island_removal_mode 0)
			)
			(polygon
				(pts
					(xy 193.9671 -99.1108) (xy 193.4591 -99.1108) (xy 193.4591 -98.3488) (xy 193.9671 -98.3488)
				)
			)
		)
		(zone
			(layer "F.Cu")
			(hatch none 0.5)
			(connect_pads
				(clearance 0)
			)
			(min_thickness 0.25)
			(keepout
				(tracks not_allowed)
				(vias allowed)
				(pads allowed)
				(copperpour not_allowed)
				(footprints allowed)
			)
			(placement
				(enabled no)
				(sheetname "")
			)
			(fill
				(thermal_gap 0.5)
				(thermal_bridge_width 0.5)
				(island_removal_mode 0)
			)
			(polygon
				(pts
					(xy 193.9671 -98.3488) (xy 193.9671 -99.1108) (xy 193.4591 -99.1108) (xy 193.4591 -98.3488)
				)
			)
		)
	)
	(footprint ""
		(layer "F.Cu")
		(at 431.378868 -125.941582 -90)
		(property "Reference" "C8B12"
			(at 0 0 270)
			(layer "F.SilkS")
			(hide yes)
			(effects
				(font
					(size 1.27 1.27)
				)
			)
		)
		(property "Value" ""
			(at 0 0 270)
			(layer "F.Fab")
			(effects
				(font
					(size 1.27 1.27)
				)
			)
		)
		(duplicate_pad_numbers_are_jumpers no)
		(fp_poly
			(pts
				(xy -0.7239 -0.2159) (xy 0.7239 -0.2159) (xy 0.7239 1.9939) (xy -0.7239 1.9939)
			)
			(stroke
				(width 0)
				(type default)
			)
			(fill no)
			(layer "F.CrtYd")
		)
		(fp_line
			(start -0.7239 1.9939)
			(end 0.7239 1.9939)
			(stroke
				(width 0.1)
				(type default)
			)
			(layer "F.Fab")
		)
		(fp_line
			(start 0.7239 1.9939)
			(end 0.7239 -0.2159)
			(stroke
				(width 0.1)
				(type default)
			)
			(layer "F.Fab")
		)
		(fp_line
			(start -0.7239 -0.2159)
			(end -0.7239 1.9939)
			(stroke
				(width 0.1)
				(type default)
			)
			(layer "F.Fab")
		)
		(fp_line
			(start 0.7239 -0.2159)
			(end -0.7239 -0.2159)
			(stroke
				(width 0.1)
				(type default)
			)
			(layer "F.Fab")
		)
		(pad "1" smd rect
			(at 0 0 270)
			(size 1.27 1.016)
			(layers "F.Cu" "F.Mask" "F.Paste")
			(net "P5V_STBY")
		)
		(pad "2" smd rect
			(at 0 1.778 270)
			(size 1.27 1.016)
			(layers "F.Cu" "F.Mask" "F.Paste")
			(net "GND")
		)
		(zone
			(layer "F.Cu")
			(hatch none 0.5)
			(connect_pads
				(clearance 0)
			)
			(min_thickness 0.25)
			(keepout
				(tracks not_allowed)
				(vias allowed)
				(pads allowed)
				(copperpour not_allowed)
				(footprints allowed)
			)
			(placement
				(enabled no)
				(sheetname "")
			)
			(fill
				(thermal_gap 0.5)
				(thermal_bridge_width 0.5)
				(island_removal_mode 0)
			)
			(polygon
				(pts
					(xy 430.870868 -126.576582) (xy 430.870868 -125.306582) (xy 430.108868 -125.306582) (xy 430.108868 -126.576582)
				)
			)
		)
	)
	(footprint ""
		(layer "F.Cu")
		(at 15.370048 -118.679976 -90)
		(property "Reference" "J1B2"
			(at -1.9558 15.89913 90)
			(unlocked yes)
			(layer "F.SilkS")
			(effects
				(font
					(size 0.7874 0.5842)
					(thickness 0.1524)
				)
			)
		)
		(property "Value" ""
			(at 0 0 270)
			(layer "F.Fab")
			(effects
				(font
					(size 1.27 1.27)
				)
			)
		)
		(duplicate_pad_numbers_are_jumpers no)
		(fp_line
			(start -3.47472 14.14526)
			(end 2.71526 14.14526)
			(stroke
				(width 0.1524)
				(type default)
			)
			(layer "F.SilkS")
		)
		(fp_line
			(start 2.71526 14.14526)
			(end 2.71526 6.1722)
			(stroke
				(width 0.1524)
				(type default)
			)
			(layer "F.SilkS")
		)
		(fp_line
			(start 2.71526 3.9878)
			(end 2.71526 -1.44526)
			(stroke
				(width 0.1524)
				(type default)
			)
			(layer "F.SilkS")
		)
		(fp_line
			(start -3.47472 -1.44526)
			(end -3.47472 14.14526)
			(stroke
				(width 0.1524)
				(type default)
			)
			(layer "F.SilkS")
		)
		(fp_line
			(start 2.71526 -1.44526)
			(end -3.47472 -1.44526)
			(stroke
				(width 0.1524)
				(type default)
			)
			(layer "F.SilkS")
		)
		(fp_poly
			(pts
				(xy -5.2578 0.4445) (xy -5.2578 -0.5715) (xy -3.9878 -0.0635)
			)
			(stroke
				(width 0)
				(type default)
			)
			(fill yes)
			(layer "F.SilkS")
		)
		(fp_poly
			(pts
				(xy -2.4511 -0.13716) (xy -2.4511 -1.15316) (xy -1.1811 -0.64516)
			)
			(stroke
				(width 0)
				(type default)
			)
			(fill yes)
			(layer "B.SilkS")
		)
		(fp_poly
			(pts
				(xy 2.71526 -1.44526) (xy 2.71526 14.14526) (xy -3.47472 14.14526) (xy -3.47472 -1.44526)
			)
			(stroke
				(width 0)
				(type default)
			)
			(fill no)
			(layer "F.CrtYd")
		)
		(fp_poly
			(pts
				(xy -5.27558 0.4445) (xy -5.27558 -0.5715) (xy -4.00558 -0.0635)
			)
			(stroke
				(width 0)
				(type default)
			)
			(fill yes)
			(layer "B.Fab")
		)
		(fp_line
			(start -3.47472 14.14526)
			(end -3.47472 -1.44526)
			(stroke
				(width 0.1)
				(type default)
			)
			(layer "F.Fab")
		)
		(fp_line
			(start 2.71526 14.14526)
			(end -3.47472 14.14526)
			(stroke
				(width 0.1)
				(type default)
			)
			(layer "F.Fab")
		)
		(fp_line
			(start -3.47472 -1.44526)
			(end 2.71526 -1.44526)
			(stroke
				(width 0.1)
				(type default)
			)
			(layer "F.Fab")
		)
		(fp_line
			(start 2.71526 -1.44526)
			(end 2.71526 14.14526)
			(stroke
				(width 0.1)
				(type default)
			)
			(layer "F.Fab")
		)
		(fp_poly
			(pts
				(xy -5.2578 0.4445) (xy -5.2578 -0.5715) (xy -3.9878 -0.0635)
			)
			(stroke
				(width 0)
				(type default)
			)
			(fill yes)
			(layer "F.Fab")
		)
		(fp_text user "6"
			(at -3.434334 15.171928 0)
			(unlocked yes)
			(layer "F.SilkS")
			(effects
				(font
					(size 0.7874 0.5842)
					(thickness 0.1524)
				)
			)
		)
		(fp_text user "6"
			(at -3.628644 13.098018 270)
			(unlocked yes)
			(layer "B.SilkS")
			(effects
				(font
					(size 0.7874 0.5842)
					(thickness 0.1524)
				)
				(justify mirror)
			)
		)
		(fp_text user "6"
			(at -4.08178 12.91209 270)
			(unlocked yes)
			(layer "B.Fab")
			(effects
				(font
					(size 0.7874 0.5842)
					(thickness 0.1524)
				)
				(justify mirror)
			)
		)
		(fp_text user "6"
			(at -1.462024 -1.9939 270)
			(unlocked yes)
			(layer "F.Fab")
			(effects
				(font
					(size 0.7874 0.5842)
					(thickness 0.1524)
				)
			)
		)
		(pad "" np_thru_hole circle
			(at 2.159 5.08 270)
			(size 0.254 0.254)
			(drill 1.4986)
			(layers "*.Cu" "*.Mask")
			(clearance 0.9398)
			(thermal_gap 0.9398)
		)
		(pad "1" thru_hole rect
			(at 0 0 270)
			(size 1.524 1.524)
			(drill 1.143)
			(layers "*.Cu" "*.Mask")
			(remove_unused_layers no)
			(net "GND")
			(clearance 0.127)
			(thermal_gap 0.127)
			(padstack
				(mode front_inner_back)
				(layer "Inner"
					(shape circle)
					(size 1.524 1.524)
					(clearance 0.127)
				)
				(layer "B.Cu"
					(shape rect)
					(size 1.524 1.524)
					(clearance 0.127)
				)
			)
		)
		(pad "2" thru_hole circle
			(at 0 2.54 270)
			(size 1.524 1.524)
			(drill 1.143)
			(layers "*.Cu" "*.Mask")
			(remove_unused_layers no)
			(net "P12V_PUMP")
			(clearance 0.127)
			(thermal_gap 0.127)
		)
		(pad "3" thru_hole circle
			(at 0 5.08 270)
			(size 1.524 1.524)
			(drill 1.143)
			(layers "*.Cu" "*.Mask")
			(remove_unused_layers no)
			(net "PUMP_TACH_D")
			(clearance 0.127)
			(thermal_gap 0.127)
		)
		(pad "4" thru_hole circle
			(at 0 7.62 270)
			(size 1.524 1.524)
			(drill 1.143)
			(layers "*.Cu" "*.Mask")
			(remove_unused_layers no)
			(net "PUMP_PWM_OUT_R")
			(clearance 0.127)
			(thermal_gap 0.127)
		)
		(pad "5" thru_hole circle
			(at 0 10.16 270)
			(size 1.524 1.524)
			(drill 1.143)
			(layers "*.Cu" "*.Mask")
			(remove_unused_layers no)
			(net "PUMP_TACH1_D")
			(clearance 0.127)
			(thermal_gap 0.127)
		)
		(pad "6" thru_hole circle
			(at 0 12.7 270)
			(size 1.524 1.524)
			(drill 1.143)
			(layers "*.Cu" "*.Mask")
			(remove_unused_layers no)
			(net "TP_PUMP")
			(clearance 0.127)
			(thermal_gap 0.127)
		)
		(zone
			(layers "F.Cu" "B.Cu" "In1.Cu" "In2.Cu" "In3.Cu" "In4.Cu" "In5.Cu" "In6.Cu"
				"In7.Cu" "In8.Cu" "In9.Cu" "In10.Cu" "In11.Cu" "In12.Cu"
			)
			(hatch none 0.5)
			(connect_pads
				(clearance 0)
			)
			(min_thickness 0.25)
			(keepout
				(tracks not_allowed)
				(vias allowed)
				(pads allowed)
				(copperpour not_allowed)
				(footprints allowed)
			)
			(placement
				(enabled no)
				(sheetname "")
			)
			(fill
				(thermal_gap 0.5)
				(thermal_bridge_width 0.5)
				(island_removal_mode 0)
			)
			(polygon
				(pts
					(arc
						(start 11.356848 -116.520976)
						(mid 9.223248 -116.520976)
						(end 11.356848 -116.520976)
					)
				)
			)
		)
	)
	(footprint ""
		(layer "F.Cu")
		(at 399.6182 1.7272 90)
		(property "Reference" "R8G23"
			(at 0 0 90)
			(layer "F.SilkS")
			(hide yes)
			(effects
				(font
					(size 1.27 1.27)
				)
			)
		)
		(property "Value" ""
			(at 0 0 90)
			(layer "F.Fab")
			(effects
				(font
					(size 1.27 1.27)
				)
			)
		)
		(duplicate_pad_numbers_are_jumpers no)
		(fp_poly
			(pts
				(xy -0.2794 -0.1016) (xy 0.2794 -0.1016) (xy 0.2794 0.9906) (xy -0.2794 0.9906)
			)
			(stroke
				(width 0)
				(type default)
			)
			(fill no)
			(layer "F.CrtYd")
		)
		(fp_line
			(start 0.2794 -0.1016)
			(end -0.2794 -0.1016)
			(stroke
				(width 0.1)
				(type default)
			)
			(layer "F.Fab")
		)
		(fp_line
			(start -0.2794 -0.1016)
			(end -0.2794 0.9906)
			(stroke
				(width 0.1)
				(type default)
			)
			(layer "F.Fab")
		)
		(fp_line
			(start 0.2794 0.9906)
			(end 0.2794 -0.1016)
			(stroke
				(width 0.1)
				(type default)
			)
			(layer "F.Fab")
		)
		(fp_line
			(start -0.2794 0.9906)
			(end 0.2794 0.9906)
			(stroke
				(width 0.1)
				(type default)
			)
			(layer "F.Fab")
		)
		(pad "1" smd rect
			(at 0 0 90)
			(size 0.508 0.508)
			(layers "F.Cu" "F.Mask" "F.Paste")
			(net "JTAG_TCK_R")
		)
		(pad "2" smd rect
			(at 0 0.889 90)
			(size 0.508 0.508)
			(layers "F.Cu" "F.Mask" "F.Paste")
			(net "GND")
		)
		(zone
			(layer "F.Cu")
			(hatch none 0.5)
			(connect_pads
				(clearance 0)
			)
			(min_thickness 0.25)
			(keepout
				(tracks allowed)
				(vias not_allowed)
				(pads allowed)
				(copperpour not_allowed)
				(footprints allowed)
			)
			(placement
				(enabled no)
				(sheetname "")
			)
			(fill
				(thermal_gap 0.5)
				(thermal_bridge_width 0.5)
				(island_removal_mode 0)
			)
			(polygon
				(pts
					(xy 399.8722 1.9812) (xy 399.8722 1.4732) (xy 400.2532 1.4732) (xy 400.2532 1.9812)
				)
			)
		)
		(zone
			(layer "F.Cu")
			(hatch none 0.5)
			(connect_pads
				(clearance 0)
			)
			(min_thickness 0.25)
			(keepout
				(tracks not_allowed)
				(vias allowed)
				(pads allowed)
				(copperpour not_allowed)
				(footprints allowed)
			)
			(placement
				(enabled no)
				(sheetname "")
			)
			(fill
				(thermal_gap 0.5)
				(thermal_bridge_width 0.5)
				(island_removal_mode 0)
			)
			(polygon
				(pts
					(xy 400.2532 1.9812) (xy 400.2532 1.4732) (xy 399.8722 1.4732) (xy 399.8722 1.9812)
				)
			)
		)
	)
	(footprint ""
		(layer "F.Cu")
		(at 155.6512 -118.364 90)
		(property "Reference" "R3B5"
			(at 0 0 90)
			(layer "F.SilkS")
			(hide yes)
			(effects
				(font
					(size 1.27 1.27)
				)
			)
		)
		(property "Value" ""
			(at 0 0 90)
			(layer "F.Fab")
			(effects
				(font
					(size 1.27 1.27)
				)
			)
		)
		(duplicate_pad_numbers_are_jumpers no)
		(fp_poly
			(pts
				(xy -0.2794 -0.1016) (xy 0.2794 -0.1016) (xy 0.2794 0.9906) (xy -0.2794 0.9906)
			)
			(stroke
				(width 0)
				(type default)
			)
			(fill no)
			(layer "F.CrtYd")
		)
		(fp_line
			(start 0.2794 -0.1016)
			(end -0.2794 -0.1016)
			(stroke
				(width 0.1)
				(type default)
			)
			(layer "F.Fab")
		)
		(fp_line
			(start -0.2794 -0.1016)
			(end -0.2794 0.9906)
			(stroke
				(width 0.1)
				(type default)
			)
			(layer "F.Fab")
		)
		(fp_line
			(start 0.2794 0.9906)
			(end 0.2794 -0.1016)
			(stroke
				(width 0.1)
				(type default)
			)
			(layer "F.Fab")
		)
		(fp_line
			(start -0.2794 0.9906)
			(end 0.2794 0.9906)
			(stroke
				(width 0.1)
				(type default)
			)
			(layer "F.Fab")
		)
		(pad "1" smd rect
			(at 0 0 90)
			(size 0.508 0.508)
			(layers "F.Cu" "F.Mask" "F.Paste")
			(net "SVID_CLK0_CPU1")
		)
		(pad "2" smd rect
			(at 0 0.889 90)
			(size 0.508 0.508)
			(layers "F.Cu" "F.Mask" "F.Paste")
			(net "SVID_CLK0_CPU1_R")
		)
		(zone
			(layer "F.Cu")
			(hatch none 0.5)
			(connect_pads
				(clearance 0)
			)
			(min_thickness 0.25)
			(keepout
				(tracks allowed)
				(vias not_allowed)
				(pads allowed)
				(copperpour not_allowed)
				(footprints allowed)
			)
			(placement
				(enabled no)
				(sheetname "")
			)
			(fill
				(thermal_gap 0.5)
				(thermal_bridge_width 0.5)
				(island_removal_mode 0)
			)
			(polygon
				(pts
					(xy 155.9052 -118.11) (xy 155.9052 -118.618) (xy 156.2862 -118.618) (xy 156.2862 -118.11)
				)
			)
		)
		(zone
			(layer "F.Cu")
			(hatch none 0.5)
			(connect_pads
				(clearance 0)
			)
			(min_thickness 0.25)
			(keepout
				(tracks not_allowed)
				(vias allowed)
				(pads allowed)
				(copperpour not_allowed)
				(footprints allowed)
			)
			(placement
				(enabled no)
				(sheetname "")
			)
			(fill
				(thermal_gap 0.5)
				(thermal_bridge_width 0.5)
				(island_removal_mode 0)
			)
			(polygon
				(pts
					(xy 156.2862 -118.11) (xy 156.2862 -118.618) (xy 155.9052 -118.618) (xy 155.9052 -118.11)
				)
			)
		)
	)
)
